# SCM (Grand Teton) — schematic netlist excerpt (pin names and nets, part order shuffled) for the footprints in the layout excerpt that follows; sources: Cadence DE-HDL packaged netlist, KiCad conversion of 12092022_DA0F0TMDCD0_F0T_Management_Board_D_brd_V3_OCP.brd

R760  Q_RES  33.2 1% CHIP  pkg 0402LF  page 13 : A = FM_BMC_CRASHLOG_TRIG_N ; B = FM_BMC_CRASHLOG_TRIG_R1_N
R93  Q_RES  33.2 1% CHIP  pkg 0402LF  page 12 : A = SMB_BMC_MM5_R_SDA ; B = SMB_BMC_MM5_SDA

(kicad_pcb
	(version 20260206)
	(generator "pcbnew")
	(generator_version "10.0")
	(general
		(thickness 1.6)
		(legacy_teardrops no)
	)
	(paper "A4")
	(title_block
		(title "12092022_DA0F0TMDCD0_F0T_Management_Board_D_brd_V3_OCP.brd")
		(comment 1 "Grand Teton / footprints 1227-1228 of 1440")
	)
	(layers
		(0 "F.Cu" signal "TOP")
		(4 "In1.Cu" signal "GND")
		(6 "In2.Cu" signal "IN1")
		(8 "In3.Cu" signal "GND1")
		(10 "In4.Cu" signal "IN2")
		(12 "In5.Cu" signal "VCC")
		(14 "In6.Cu" signal "VCC1")
		(16 "In7.Cu" signal "IN3")
		(18 "In8.Cu" signal "GND2")
		(20 "In9.Cu" signal "IN4")
		(22 "In10.Cu" signal "GND3")
		(2 "B.Cu" signal "BOTTOM")
		(9 "F.Adhes" user "F.Adhesive")
		(11 "B.Adhes" user "B.Adhesive")
		(13 "F.Paste" user "Package Geometry/Pastemask Top")
		(15 "B.Paste" user "Package Geometry/Pastemask Bottom")
		(5 "F.SilkS" user "Ref Des/Silkscreen Top")
		(7 "B.SilkS" user "Ref Des/Silkscreen Bottom")
		(1 "F.Mask" user "Board Geometry/Soldermask Top")
		(3 "B.Mask" user "Board Geometry/Soldermask Bottom")
		(17 "Dwgs.User" user "User.Drawings")
		(19 "Cmts.User" user "User.Comments")
		(21 "Eco1.User" user "User.Eco1")
		(23 "Eco2.User" user "User.Eco2")
		(25 "Edge.Cuts" user "Board Geometry/Outline")
		(27 "Margin" user)
		(31 "F.CrtYd" user "Package Geometry/Place Bound Top")
		(29 "B.CrtYd" user "Package Geometry/Place Bound Bottom")
		(35 "F.Fab" user "Ref Des/Assembly Top")
		(33 "B.Fab" user "Ref Des/Assembly Bottom")
	)
	(footprint ""
		(layer "B.Cu")
		(at 59.81954 -30.867604 90)
		(property "Reference" "R93"
			(at 0 0 90)
			(layer "B.SilkS")
			(hide yes)
			(effects
				(font
					(size 1.27 1.27)
				)
				(justify mirror)
			)
		)
		(property "Value" ""
			(at 0 0 90)
			(layer "B.Fab")
			(effects
				(font
					(size 1.27 1.27)
				)
				(justify mirror)
			)
		)
		(duplicate_pad_numbers_are_jumpers no)
		(fp_line
			(start 0.7874 -0.4064)
			(end -0.7874 -0.4064)
			(stroke
				(width 0.1524)
				(type default)
			)
			(layer "B.SilkS")
		)
		(fp_line
			(start -0.7874 -0.4064)
			(end -0.7874 0.4064)
			(stroke
				(width 0.1524)
				(type default)
			)
			(layer "B.SilkS")
		)
		(fp_line
			(start 0.7874 0.4064)
			(end 0.7874 -0.4064)
			(stroke
				(width 0.1524)
				(type default)
			)
			(layer "B.SilkS")
		)
		(fp_line
			(start -0.7874 0.4064)
			(end 0.7874 0.4064)
			(stroke
				(width 0.1524)
				(type default)
			)
			(layer "B.SilkS")
		)
		(fp_line
			(start 0.67945 -0.305054)
			(end 0.12065 -0.305054)
			(stroke
				(width 0.1)
				(type default)
			)
			(layer "B.Fab")
		)
		(fp_line
			(start 0.12065 -0.305054)
			(end 0.12065 -0.2794)
			(stroke
				(width 0.1)
				(type default)
			)
			(layer "B.Fab")
		)
		(fp_line
			(start -0.12065 -0.3048)
			(end -0.67945 -0.3048)
			(stroke
				(width 0.1)
				(type default)
			)
			(layer "B.Fab")
		)
		(fp_line
			(start -0.67945 -0.3048)
			(end -0.67945 0.3048)
			(stroke
				(width 0.1)
				(type default)
			)
			(layer "B.Fab")
		)
		(fp_line
			(start 0.12065 -0.2794)
			(end -0.12065 -0.2794)
			(stroke
				(width 0.1)
				(type default)
			)
			(layer "B.Fab")
		)
		(fp_line
			(start -0.12065 -0.2794)
			(end -0.12065 -0.3048)
			(stroke
				(width 0.1)
				(type default)
			)
			(layer "B.Fab")
		)
		(fp_line
			(start 0.12065 0.2794)
			(end 0.12065 0.3048)
			(stroke
				(width 0.1)
				(type default)
			)
			(layer "B.Fab")
		)
		(fp_line
			(start -0.120396 0.2794)
			(end 0.12065 0.2794)
			(stroke
				(width 0.1)
				(type default)
			)
			(layer "B.Fab")
		)
		(fp_line
			(start 0.67945 0.3048)
			(end 0.67945 -0.305054)
			(stroke
				(width 0.1)
				(type default)
			)
			(layer "B.Fab")
		)
		(fp_line
			(start 0.12065 0.3048)
			(end 0.67945 0.3048)
			(stroke
				(width 0.1)
				(type default)
			)
			(layer "B.Fab")
		)
		(fp_line
			(start -0.120396 0.3048)
			(end -0.120396 0.2794)
			(stroke
				(width 0.1)
				(type default)
			)
			(layer "B.Fab")
		)
		(fp_line
			(start -0.67945 0.3048)
			(end -0.120396 0.3048)
			(stroke
				(width 0.1)
				(type default)
			)
			(layer "B.Fab")
		)
		(pad "1" smd circle
			(at 0.40005 0 270)
			(size 0 0)
			(layers "B.Cu" "B.Mask" "B.Paste")
			(net "SMB_BMC_MM5_R_SDA")
		)
		(pad "2" smd circle
			(at -0.40005 0 270)
			(size 0 0)
			(layers "B.Cu" "B.Mask" "B.Paste")
			(net "SMB_BMC_MM5_SDA")
		)
	)
	(footprint ""
		(layer "B.Cu")
		(at 41.1988 -37.338 180)
		(property "Reference" "R760"
			(at 0 0 0)
			(layer "B.SilkS")
			(hide yes)
			(effects
				(font
					(size 1.27 1.27)
				)
				(justify mirror)
			)
		)
		(property "Value" ""
			(at 0 0 0)
			(layer "B.Fab")
			(effects
				(font
					(size 1.27 1.27)
				)
				(justify mirror)
			)
		)
		(duplicate_pad_numbers_are_jumpers no)
		(fp_line
			(start 0.7874 0.4064)
			(end 0.7874 -0.4064)
			(stroke
				(width 0.1524)
				(type default)
			)
			(layer "B.SilkS")
		)
		(fp_line
			(start 0.7874 -0.4064)
			(end -0.7874 -0.4064)
			(stroke
				(width 0.1524)
				(type default)
			)
			(layer "B.SilkS")
		)
		(fp_line
			(start -0.7874 0.4064)
			(end 0.7874 0.4064)
			(stroke
				(width 0.1524)
				(type default)
			)
			(layer "B.SilkS")
		)
		(fp_line
			(start -0.7874 -0.4064)
			(end -0.7874 0.4064)
			(stroke
				(width 0.1524)
				(type default)
			)
			(layer "B.SilkS")
		)
		(fp_line
			(start 0.67945 0.3048)
			(end 0.67945 -0.305054)
			(stroke
				(width 0.1)
				(type default)
			)
			(layer "B.Fab")
		)
		(fp_line
			(start 0.67945 -0.305054)
			(end 0.12065 -0.305054)
			(stroke
				(width 0.1)
				(type default)
			)
			(layer "B.Fab")
		)
		(fp_line
			(start 0.12065 0.3048)
			(end 0.67945 0.3048)
			(stroke
				(width 0.1)
				(type default)
			)
			(layer "B.Fab")
		)
		(fp_line
			(start 0.12065 0.2794)
			(end 0.12065 0.3048)
			(stroke
				(width 0.1)
				(type default)
			)
			(layer "B.Fab")
		)
		(fp_line
			(start 0.12065 -0.2794)
			(end -0.12065 -0.2794)
			(stroke
				(width 0.1)
				(type default)
			)
			(layer "B.Fab")
		)
		(fp_line
			(start 0.12065 -0.305054)
			(end 0.12065 -0.2794)
			(stroke
				(width 0.1)
				(type default)
			)
			(layer "B.Fab")
		)
		(fp_line
			(start -0.120396 0.3048)
			(end -0.120396 0.2794)
			(stroke
				(width 0.1)
				(type default)
			)
			(layer "B.Fab")
		)
		(fp_line
			(start -0.120396 0.2794)
			(end 0.12065 0.2794)
			(stroke
				(width 0.1)
				(type default)
			)
			(layer "B.Fab")
		)
		(fp_line
			(start -0.12065 -0.2794)
			(end -0.12065 -0.3048)
			(stroke
				(width 0.1)
				(type default)
			)
			(layer "B.Fab")
		)
		(fp_line
			(start -0.12065 -0.3048)
			(end -0.67945 -0.3048)
			(stroke
				(width 0.1)
				(type default)
			)
			(layer "B.Fab")
		)
		(fp_line
			(start -0.67945 0.3048)
			(end -0.120396 0.3048)
			(stroke
				(width 0.1)
				(type default)
			)
			(layer "B.Fab")
		)
		(fp_line
			(start -0.67945 -0.3048)
			(end -0.67945 0.3048)
			(stroke
				(width 0.1)
				(type default)
			)
			(layer "B.Fab")
		)
		(pad "1" smd circle
			(at 0.40005 0)
			(size 0 0)
			(layers "B.Cu" "B.Mask" "B.Paste")
			(net "FM_BMC_CRASHLOG_TRIG_N")
		)
		(pad "2" smd circle
			(at -0.40005 0)
			(size 0 0)
			(layers "B.Cu" "B.Mask" "B.Paste")
			(net "FM_BMC_CRASHLOG_TRIG_R1_N")
		)
	)
)
